(kicad_pcb
	(version 20260206)
	(generator "pcbnew")
	(generator_version "10.0")
	(general
		(thickness 1.6)
		(legacy_teardrops no)
	)
	(paper "A4")
	(title_block
		(title "01162023_DA0F0TEBIF0_F0T_Expander_BD_F_brd_V02_OCP.brd")
		(comment 1 "Grand Teton / footprints 6391-6395 of 9728")
	)
	(layers
		(0 "F.Cu" signal "TOP")
		(4 "In1.Cu" signal "GND")
		(6 "In2.Cu" signal "VCC")
		(8 "In3.Cu" signal "VCC1")
		(10 "In4.Cu" signal "GND1")
		(12 "In5.Cu" signal "IN1")
		(14 "In6.Cu" signal "GND2")
		(16 "In7.Cu" signal "IN2")
		(18 "In8.Cu" signal "GND3")
		(20 "In9.Cu" signal "IN3")
		(22 "In10.Cu" signal "GND4")
		(24 "In11.Cu" signal "IN4")
		(26 "In12.Cu" signal "GND5")
		(28 "In13.Cu" signal "IN5")
		(30 "In14.Cu" signal "GND6")
		(32 "In15.Cu" signal "IN6")
		(34 "In16.Cu" signal "GND7")
		(2 "B.Cu" signal "BOTTOM")
		(9 "F.Adhes" user "F.Adhesive")
		(11 "B.Adhes" user "B.Adhesive")
		(13 "F.Paste" user "Package Geometry/Pastemask Top")
		(15 "B.Paste" user "Package Geometry/Pastemask Bottom")
		(5 "F.SilkS" user "Ref Des/Silkscreen Top")
		(7 "B.SilkS" user "Ref Des/Silkscreen Bottom")
		(1 "F.Mask" user "Board Geometry/Soldermask Top")
		(3 "B.Mask" user "Board Geometry/Soldermask Bottom")
		(17 "Dwgs.User" user "User.Drawings")
		(19 "Cmts.User" user "User.Comments")
		(21 "Eco1.User" user "User.Eco1")
		(23 "Eco2.User" user "User.Eco2")
		(25 "Edge.Cuts" user "Board Geometry/Outline")
		(27 "Margin" user)
		(31 "F.CrtYd" user "Package Geometry/Place Bound Top")
		(29 "B.CrtYd" user "Package Geometry/Place Bound Bottom")
		(35 "F.Fab" user "Ref Des/Assembly Top")
		(33 "B.Fab" user "Ref Des/Assembly Bottom")
	)
	(footprint ""
		(layer "F.Cu")
		(at 187.598558 -66.32194 -90)
		(property "Reference" "PC853"
			(at 0 0 270)
			(layer "F.SilkS")
			(hide yes)
			(effects
				(font
					(size 1.27 1.27)
				)
			)
		)
		(property "Value" ""
			(at 0 0 270)
			(layer "F.Fab")
			(effects
				(font
					(size 1.27 1.27)
				)
			)
		)
		(duplicate_pad_numbers_are_jumpers no)
		(fp_line
			(start -0.7874 0.4064)
			(end -0.7874 -0.4064)
			(stroke
				(width 0.1524)
				(type default)
			)
			(layer "F.SilkS")
		)
		(fp_line
			(start 0.7874 0.4064)
			(end -0.7874 0.4064)
			(stroke
				(width 0.1524)
				(type default)
			)
			(layer "F.SilkS")
		)
		(fp_line
			(start -0.7874 -0.4064)
			(end 0.7874 -0.4064)
			(stroke
				(width 0.1524)
				(type default)
			)
			(layer "F.SilkS")
		)
		(fp_line
			(start 0.7874 -0.4064)
			(end 0.7874 0.4064)
			(stroke
				(width 0.1524)
				(type default)
			)
			(layer "F.SilkS")
		)
		(fp_line
			(start -0.67945 0.3048)
			(end -0.67945 -0.305054)
			(stroke
				(width 0.1)
				(type default)
			)
			(layer "F.Fab")
		)
		(fp_line
			(start -0.12065 0.3048)
			(end -0.67945 0.3048)
			(stroke
				(width 0.1)
				(type default)
			)
			(layer "F.Fab")
		)
		(fp_line
			(start 0.120396 0.3048)
			(end 0.120396 0.2794)
			(stroke
				(width 0.1)
				(type default)
			)
			(layer "F.Fab")
		)
		(fp_line
			(start 0.67945 0.3048)
			(end 0.120396 0.3048)
			(stroke
				(width 0.1)
				(type default)
			)
			(layer "F.Fab")
		)
		(fp_line
			(start -0.12065 0.2794)
			(end -0.12065 0.3048)
			(stroke
				(width 0.1)
				(type default)
			)
			(layer "F.Fab")
		)
		(fp_line
			(start 0.120396 0.2794)
			(end -0.12065 0.2794)
			(stroke
				(width 0.1)
				(type default)
			)
			(layer "F.Fab")
		)
		(fp_line
			(start -0.12065 -0.2794)
			(end 0.12065 -0.2794)
			(stroke
				(width 0.1)
				(type default)
			)
			(layer "F.Fab")
		)
		(fp_line
			(start 0.12065 -0.2794)
			(end 0.12065 -0.3048)
			(stroke
				(width 0.1)
				(type default)
			)
			(layer "F.Fab")
		)
		(fp_line
			(start 0.12065 -0.3048)
			(end 0.67945 -0.3048)
			(stroke
				(width 0.1)
				(type default)
			)
			(layer "F.Fab")
		)
		(fp_line
			(start 0.67945 -0.3048)
			(end 0.67945 0.3048)
			(stroke
				(width 0.1)
				(type default)
			)
			(layer "F.Fab")
		)
		(fp_line
			(start -0.67945 -0.305054)
			(end -0.12065 -0.305054)
			(stroke
				(width 0.1)
				(type default)
			)
			(layer "F.Fab")
		)
		(fp_line
			(start -0.12065 -0.305054)
			(end -0.12065 -0.2794)
			(stroke
				(width 0.1)
				(type default)
			)
			(layer "F.Fab")
		)
		(pad "1" smd circle
			(at -0.40005 0 270)
			(size 0 0)
			(layers "F.Cu" "F.Mask" "F.Paste")
			(net "P12V_SSD6_CO_GATE")
		)
		(pad "2" smd circle
			(at 0.40005 0 270)
			(size 0 0)
			(layers "F.Cu" "F.Mask" "F.Paste")
			(net "GND")
		)
	)
	(footprint ""
		(layer "F.Cu")
		(at 452.694802 -246.92864 -90)
		(property "Reference" "C4430"
			(at 0 0 270)
			(layer "F.SilkS")
			(hide yes)
			(effects
				(font
					(size 1.27 1.27)
				)
			)
		)
		(property "Value" ""
			(at 0 0 270)
			(layer "F.Fab")
			(effects
				(font
					(size 1.27 1.27)
				)
			)
		)
		(duplicate_pad_numbers_are_jumpers no)
		(fp_line
			(start -1.524 0.762)
			(end -1.524 -0.762)
			(stroke
				(width 0.1524)
				(type default)
			)
			(layer "F.SilkS")
		)
		(fp_line
			(start 1.524 0.762)
			(end -1.524 0.762)
			(stroke
				(width 0.1524)
				(type default)
			)
			(layer "F.SilkS")
		)
		(fp_line
			(start -1.524 -0.762)
			(end 1.524 -0.762)
			(stroke
				(width 0.1524)
				(type default)
			)
			(layer "F.SilkS")
		)
		(fp_line
			(start 1.524 -0.762)
			(end 1.524 0.762)
			(stroke
				(width 0.1524)
				(type default)
			)
			(layer "F.SilkS")
		)
		(fp_line
			(start -1.1049 0.724916)
			(end 1.1049 0.724916)
			(stroke
				(width 0.1)
				(type default)
			)
			(layer "F.Fab")
		)
		(fp_line
			(start 1.1049 0.724916)
			(end 1.1049 -0.724916)
			(stroke
				(width 0.1)
				(type default)
			)
			(layer "F.Fab")
		)
		(fp_line
			(start -1.1049 -0.724916)
			(end -1.1049 0.724916)
			(stroke
				(width 0.1)
				(type default)
			)
			(layer "F.Fab")
		)
		(fp_line
			(start 1.1049 -0.724916)
			(end -1.1049 -0.724916)
			(stroke
				(width 0.1)
				(type default)
			)
			(layer "F.Fab")
		)
		(pad "1" smd rect
			(at -0.889 0 90)
			(size 1.016 1.27)
			(layers "F.Cu" "F.Mask" "F.Paste")
			(net "P3V3_AUX")
		)
		(pad "2" smd rect
			(at 0.889 0 90)
			(size 1.016 1.27)
			(layers "F.Cu" "F.Mask" "F.Paste")
			(net "GND")
		)
	)
	(footprint ""
		(layer "F.Cu")
		(at 198.564246 -362.567728 180)
		(property "Reference" "PC6"
			(at 0 0 180)
			(layer "F.SilkS")
			(hide yes)
			(effects
				(font
					(size 1.27 1.27)
				)
			)
		)
		(property "Value" ""
			(at 0 0 180)
			(layer "F.Fab")
			(effects
				(font
					(size 1.27 1.27)
				)
			)
		)
		(duplicate_pad_numbers_are_jumpers no)
		(fp_line
			(start 0.7874 0.4064)
			(end -0.7874 0.4064)
			(stroke
				(width 0.1524)
				(type default)
			)
			(layer "F.SilkS")
		)
		(fp_line
			(start 0.7874 -0.4064)
			(end 0.7874 0.4064)
			(stroke
				(width 0.1524)
				(type default)
			)
			(layer "F.SilkS")
		)
		(fp_line
			(start -0.7874 0.4064)
			(end -0.7874 -0.4064)
			(stroke
				(width 0.1524)
				(type default)
			)
			(layer "F.SilkS")
		)
		(fp_line
			(start -0.7874 -0.4064)
			(end 0.7874 -0.4064)
			(stroke
				(width 0.1524)
				(type default)
			)
			(layer "F.SilkS")
		)
		(fp_line
			(start 0.67945 0.3048)
			(end 0.120396 0.3048)
			(stroke
				(width 0.1)
				(type default)
			)
			(layer "F.Fab")
		)
		(fp_line
			(start 0.67945 -0.3048)
			(end 0.67945 0.3048)
			(stroke
				(width 0.1)
				(type default)
			)
			(layer "F.Fab")
		)
		(fp_line
			(start 0.12065 -0.2794)
			(end 0.12065 -0.3048)
			(stroke
				(width 0.1)
				(type default)
			)
			(layer "F.Fab")
		)
		(fp_line
			(start 0.12065 -0.3048)
			(end 0.67945 -0.3048)
			(stroke
				(width 0.1)
				(type default)
			)
			(layer "F.Fab")
		)
		(fp_line
			(start 0.120396 0.3048)
			(end 0.120396 0.2794)
			(stroke
				(width 0.1)
				(type default)
			)
			(layer "F.Fab")
		)
		(fp_line
			(start 0.120396 0.2794)
			(end -0.12065 0.2794)
			(stroke
				(width 0.1)
				(type default)
			)
			(layer "F.Fab")
		)
		(fp_line
			(start -0.12065 0.3048)
			(end -0.67945 0.3048)
			(stroke
				(width 0.1)
				(type default)
			)
			(layer "F.Fab")
		)
		(fp_line
			(start -0.12065 0.2794)
			(end -0.12065 0.3048)
			(stroke
				(width 0.1)
				(type default)
			)
			(layer "F.Fab")
		)
		(fp_line
			(start -0.12065 -0.2794)
			(end 0.12065 -0.2794)
			(stroke
				(width 0.1)
				(type default)
			)
			(layer "F.Fab")
		)
		(fp_line
			(start -0.12065 -0.305054)
			(end -0.12065 -0.2794)
			(stroke
				(width 0.1)
				(type default)
			)
			(layer "F.Fab")
		)
		(fp_line
			(start -0.67945 0.3048)
			(end -0.67945 -0.305054)
			(stroke
				(width 0.1)
				(type default)
			)
			(layer "F.Fab")
		)
		(fp_line
			(start -0.67945 -0.305054)
			(end -0.12065 -0.305054)
			(stroke
				(width 0.1)
				(type default)
			)
			(layer "F.Fab")
		)
		(pad "1" smd circle
			(at -0.40005 0 180)
			(size 0 0)
			(layers "F.Cu" "F.Mask" "F.Paste")
			(net "HSC_IMON")
		)
		(pad "2" smd circle
			(at 0.40005 0 180)
			(size 0 0)
			(layers "F.Cu" "F.Mask" "F.Paste")
			(net "AGND_HSC")
		)
	)
	(footprint ""
		(layer "F.Cu")
		(at 461.748886 -267.009626)
		(property "Reference" "C4393"
			(at 0 0 0)
			(layer "F.SilkS")
			(hide yes)
			(effects
				(font
					(size 1.27 1.27)
				)
			)
		)
		(property "Value" ""
			(at 0 0 0)
			(layer "F.Fab")
			(effects
				(font
					(size 1.27 1.27)
				)
			)
		)
		(duplicate_pad_numbers_are_jumpers no)
		(fp_line
			(start -0.299974 -0.150114)
			(end 0.299974 -0.150114)
			(stroke
				(width 0.1)
				(type default)
			)
			(layer "F.Fab")
		)
		(fp_line
			(start -0.299974 0.150114)
			(end -0.299974 -0.150114)
			(stroke
				(width 0.1)
				(type default)
			)
			(layer "F.Fab")
		)
		(fp_line
			(start 0.299974 -0.150114)
			(end 0.299974 0.150114)
			(stroke
				(width 0.1)
				(type default)
			)
			(layer "F.Fab")
		)
		(fp_line
			(start 0.299974 0.150114)
			(end -0.299974 0.150114)
			(stroke
				(width 0.1)
				(type default)
			)
			(layer "F.Fab")
		)
		(pad "1" smd rect
			(at -0.2667 0)
			(size 0.3048 0.381)
			(layers "F.Cu" "F.Mask" "F.Paste")
			(net "P1V25_SERDES_VDDPLL_PEX3")
		)
		(pad "2" smd rect
			(at 0.2667 0)
			(size 0.3048 0.381)
			(layers "F.Cu" "F.Mask" "F.Paste")
			(net "GND")
		)
	)
	(footprint ""
		(layer "F.Cu")
		(at 451.669658 -366.295432 90)
		(property "Reference" "R6691"
			(at 0 0 90)
			(layer "F.SilkS")
			(hide yes)
			(effects
				(font
					(size 1.27 1.27)
				)
			)
		)
		(property "Value" ""
			(at 0 0 90)
			(layer "F.Fab")
			(effects
				(font
					(size 1.27 1.27)
				)
			)
		)
		(duplicate_pad_numbers_are_jumpers no)
		(fp_line
			(start 0.7874 -0.4064)
			(end 0.7874 0.4064)
			(stroke
				(width 0.1524)
				(type default)
			)
			(layer "F.SilkS")
		)
		(fp_line
			(start -0.7874 -0.4064)
			(end 0.7874 -0.4064)
			(stroke
				(width 0.1524)
				(type default)
			)
			(layer "F.SilkS")
		)
		(fp_line
			(start 0.7874 0.4064)
			(end -0.7874 0.4064)
			(stroke
				(width 0.1524)
				(type default)
			)
			(layer "F.SilkS")
		)
		(fp_line
			(start -0.7874 0.4064)
			(end -0.7874 -0.4064)
			(stroke
				(width 0.1524)
				(type default)
			)
			(layer "F.SilkS")
		)
		(fp_line
			(start -0.12065 -0.305054)
			(end -0.12065 -0.2794)
			(stroke
				(width 0.1)
				(type default)
			)
			(layer "F.Fab")
		)
		(fp_line
			(start -0.67945 -0.305054)
			(end -0.12065 -0.305054)
			(stroke
				(width 0.1)
				(type default)
			)
			(layer "F.Fab")
		)
		(fp_line
			(start 0.67945 -0.3048)
			(end 0.67945 0.3048)
			(stroke
				(width 0.1)
				(type default)
			)
			(layer "F.Fab")
		)
		(fp_line
			(start 0.12065 -0.3048)
			(end 0.67945 -0.3048)
			(stroke
				(width 0.1)
				(type default)
			)
			(layer "F.Fab")
		)
		(fp_line
			(start 0.12065 -0.2794)
			(end 0.12065 -0.3048)
			(stroke
				(width 0.1)
				(type default)
			)
			(layer "F.Fab")
		)
		(fp_line
			(start -0.12065 -0.2794)
			(end 0.12065 -0.2794)
			(stroke
				(width 0.1)
				(type default)
			)
			(layer "F.Fab")
		)
		(fp_line
			(start 0.120396 0.2794)
			(end -0.12065 0.2794)
			(stroke
				(width 0.1)
				(type default)
			)
			(layer "F.Fab")
		)
		(fp_line
			(start -0.12065 0.2794)
			(end -0.12065 0.3048)
			(stroke
				(width 0.1)
				(type default)
			)
			(layer "F.Fab")
		)
		(fp_line
			(start 0.67945 0.3048)
			(end 0.120396 0.3048)
			(stroke
				(width 0.1)
				(type default)
			)
			(layer "F.Fab")
		)
		(fp_line
			(start 0.120396 0.3048)
			(end 0.120396 0.2794)
			(stroke
				(width 0.1)
				(type default)
			)
			(layer "F.Fab")
		)
		(fp_line
			(start -0.12065 0.3048)
			(end -0.67945 0.3048)
			(stroke
				(width 0.1)
				(type default)
			)
			(layer "F.Fab")
		)
		(fp_line
			(start -0.67945 0.3048)
			(end -0.67945 -0.305054)
			(stroke
				(width 0.1)
				(type default)
			)
			(layer "F.Fab")
		)
		(pad "1" smd circle
			(at -0.40005 0 90)
			(size 0 0)
			(layers "F.Cu" "F.Mask" "F.Paste")
			(net "P3V3_AUX")
		)
		(pad "2" smd circle
			(at 0.40005 0 90)
			(size 0 0)
			(layers "F.Cu" "F.Mask" "F.Paste")
			(net "GPU_3V3IO_RSVD4")
		)
	)
)
